# T6G (Grand Teton) — schematic netlist excerpt (pin names and nets, part order shuffled) for the footprints in the layout excerpt that follows; sources: Cadence DE-HDL packaged netlist, KiCad conversion of 04192023_DAF0TMB3IC0_F0TG_MB_C_brd_V02_OCP.brd

C361  Q_CAP  0.1UF 16V 10% X7R  pkg C0402  page 83 : A = P3V3_AUX ; B = GND
R6126  Q_RES  1K 1% CHIP  pkg 0402LF  page 84 : A = FM_BOARD_SKU_ID3 ; B = GND

(kicad_pcb
	(version 20260206)
	(generator "pcbnew")
	(generator_version "10.0")
	(general
		(thickness 1.6)
		(legacy_teardrops no)
	)
	(paper "A4")
	(title_block
		(title "04192023_DAF0TMB3IC0_F0TG_MB_C_brd_V02_OCP.brd")
		(comment 1 "Grand Teton / footprints 6766-6767 of 8354")
	)
	(layers
		(0 "F.Cu" signal "TOP")
		(4 "In1.Cu" signal "GND")
		(6 "In2.Cu" signal "IN1")
		(8 "In3.Cu" signal "GND1")
		(10 "In4.Cu" signal "IN2")
		(12 "In5.Cu" signal "GND2")
		(14 "In6.Cu" signal "IN3")
		(16 "In7.Cu" signal "GND3")
		(18 "In8.Cu" signal "VCC")
		(20 "In9.Cu" signal "VCC1")
		(22 "In10.Cu" signal "GND4")
		(24 "In11.Cu" signal "IN4")
		(26 "In12.Cu" signal "GND5")
		(28 "In13.Cu" signal "IN5")
		(30 "In14.Cu" signal "GND6")
		(32 "In15.Cu" signal "IN6")
		(34 "In16.Cu" signal "GND7")
		(2 "B.Cu" signal "BOTTOM")
		(9 "F.Adhes" user "F.Adhesive")
		(11 "B.Adhes" user "B.Adhesive")
		(13 "F.Paste" user "Package Geometry/Pastemask Top")
		(15 "B.Paste" user "Package Geometry/Pastemask Bottom")
		(5 "F.SilkS" user "Ref Des/Silkscreen Top")
		(7 "B.SilkS" user "Ref Des/Silkscreen Bottom")
		(1 "F.Mask" user "Board Geometry/Soldermask Top")
		(3 "B.Mask" user "Board Geometry/Soldermask Bottom")
		(17 "Dwgs.User" user "User.Drawings")
		(19 "Cmts.User" user "User.Comments")
		(21 "Eco1.User" user "User.Eco1")
		(23 "Eco2.User" user "User.Eco2")
		(25 "Edge.Cuts" user "Board Geometry/Outline")
		(27 "Margin" user)
		(31 "F.CrtYd" user "Package Geometry/Place Bound Top")
		(29 "B.CrtYd" user "Package Geometry/Place Bound Bottom")
		(35 "F.Fab" user "Ref Des/Assembly Top")
		(33 "B.Fab" user "Ref Des/Assembly Bottom")
	)
	(footprint ""
		(layer "B.Cu")
		(at 188.712094 -115.022376)
		(property "Reference" "C361"
			(at 0 0 0)
			(layer "B.SilkS")
			(hide yes)
			(effects
				(font
					(size 1.27 1.27)
				)
				(justify mirror)
			)
		)
		(property "Value" ""
			(at 0 0 0)
			(layer "B.Fab")
			(effects
				(font
					(size 1.27 1.27)
				)
				(justify mirror)
			)
		)
		(duplicate_pad_numbers_are_jumpers no)
		(fp_line
			(start -0.69215 -0.2921)
			(end -0.69215 0.2921)
			(stroke
				(width 0.1524)
				(type default)
			)
			(layer "B.SilkS")
		)
		(fp_line
			(start -0.69215 0.2921)
			(end 0.69215 0.2921)
			(stroke
				(width 0.1524)
				(type default)
			)
			(layer "B.SilkS")
		)
		(fp_line
			(start 0.69215 -0.2921)
			(end -0.69215 -0.2921)
			(stroke
				(width 0.1524)
				(type default)
			)
			(layer "B.SilkS")
		)
		(fp_line
			(start 0.69215 0.2921)
			(end 0.69215 -0.2921)
			(stroke
				(width 0.1524)
				(type default)
			)
			(layer "B.SilkS")
		)
		(fp_line
			(start -0.51435 -0.2794)
			(end -0.51435 0.2794)
			(stroke
				(width 0.1)
				(type default)
			)
			(layer "B.Fab")
		)
		(fp_line
			(start -0.51435 0.2794)
			(end 0.51435 0.2794)
			(stroke
				(width 0.1)
				(type default)
			)
			(layer "B.Fab")
		)
		(fp_line
			(start 0.51435 -0.2794)
			(end -0.51435 -0.2794)
			(stroke
				(width 0.1)
				(type default)
			)
			(layer "B.Fab")
		)
		(fp_line
			(start 0.51435 0.2794)
			(end 0.51435 -0.2794)
			(stroke
				(width 0.1)
				(type default)
			)
			(layer "B.Fab")
		)
		(pad "1" smd circle
			(at 0.40005 0 180)
			(size 0 0)
			(layers "B.Cu" "B.Mask" "B.Paste")
			(net "P3V3_AUX")
		)
		(pad "2" smd circle
			(at -0.40005 0 180)
			(size 0 0)
			(layers "B.Cu" "B.Mask" "B.Paste")
			(net "GND")
		)
		(zone
			(layer "B.Cu")
			(hatch none 0.5)
			(connect_pads
				(clearance 0)
			)
			(min_thickness 0.25)
			(keepout
				(tracks not_allowed)
				(vias allowed)
				(pads allowed)
				(copperpour not_allowed)
				(footprints allowed)
			)
			(placement
				(enabled no)
				(sheetname "")
			)
			(fill
				(thermal_gap 0.5)
				(thermal_bridge_width 0.5)
				(island_removal_mode 0)
			)
			(polygon
				(pts
					(xy 188.521594 -114.934746) (xy 188.521594 -115.110006) (xy 188.611764 -115.168426) (xy 188.811154 -115.168426)
					(xy 188.902594 -115.11026) (xy 188.902594 -114.934746) (xy 188.811154 -114.87658) (xy 188.611764 -114.87658)
				)
			)
		)
	)
	(footprint ""
		(layer "B.Cu")
		(at 403.377146 -354.439728 -90)
		(property "Reference" "R6126"
			(at 0 0 90)
			(layer "B.SilkS")
			(hide yes)
			(effects
				(font
					(size 1.27 1.27)
				)
				(justify mirror)
			)
		)
		(property "Value" ""
			(at 0 0 90)
			(layer "B.Fab")
			(effects
				(font
					(size 1.27 1.27)
				)
				(justify mirror)
			)
		)
		(duplicate_pad_numbers_are_jumpers no)
		(fp_line
			(start -0.7874 0.4064)
			(end 0.7874 0.4064)
			(stroke
				(width 0.1524)
				(type default)
			)
			(layer "B.SilkS")
		)
		(fp_line
			(start 0.7874 0.4064)
			(end 0.7874 -0.4064)
			(stroke
				(width 0.1524)
				(type default)
			)
			(layer "B.SilkS")
		)
		(fp_line
			(start -0.7874 -0.4064)
			(end -0.7874 0.4064)
			(stroke
				(width 0.1524)
				(type default)
			)
			(layer "B.SilkS")
		)
		(fp_line
			(start 0.7874 -0.4064)
			(end -0.7874 -0.4064)
			(stroke
				(width 0.1524)
				(type default)
			)
			(layer "B.SilkS")
		)
		(fp_line
			(start -0.67945 0.3048)
			(end -0.120396 0.3048)
			(stroke
				(width 0.1)
				(type default)
			)
			(layer "B.Fab")
		)
		(fp_line
			(start -0.120396 0.3048)
			(end -0.120396 0.2794)
			(stroke
				(width 0.1)
				(type default)
			)
			(layer "B.Fab")
		)
		(fp_line
			(start 0.12065 0.3048)
			(end 0.67945 0.3048)
			(stroke
				(width 0.1)
				(type default)
			)
			(layer "B.Fab")
		)
		(fp_line
			(start 0.67945 0.3048)
			(end 0.67945 -0.305054)
			(stroke
				(width 0.1)
				(type default)
			)
			(layer "B.Fab")
		)
		(fp_line
			(start -0.120396 0.2794)
			(end 0.12065 0.2794)
			(stroke
				(width 0.1)
				(type default)
			)
			(layer "B.Fab")
		)
		(fp_line
			(start 0.12065 0.2794)
			(end 0.12065 0.3048)
			(stroke
				(width 0.1)
				(type default)
			)
			(layer "B.Fab")
		)
		(fp_line
			(start -0.12065 -0.2794)
			(end -0.12065 -0.3048)
			(stroke
				(width 0.1)
				(type default)
			)
			(layer "B.Fab")
		)
		(fp_line
			(start 0.12065 -0.2794)
			(end -0.12065 -0.2794)
			(stroke
				(width 0.1)
				(type default)
			)
			(layer "B.Fab")
		)
		(fp_line
			(start -0.67945 -0.3048)
			(end -0.67945 0.3048)
			(stroke
				(width 0.1)
				(type default)
			)
			(layer "B.Fab")
		)
		(fp_line
			(start -0.12065 -0.3048)
			(end -0.67945 -0.3048)
			(stroke
				(width 0.1)
				(type default)
			)
			(layer "B.Fab")
		)
		(fp_line
			(start 0.12065 -0.305054)
			(end 0.12065 -0.2794)
			(stroke
				(width 0.1)
				(type default)
			)
			(layer "B.Fab")
		)
		(fp_line
			(start 0.67945 -0.305054)
			(end 0.12065 -0.305054)
			(stroke
				(width 0.1)
				(type default)
			)
			(layer "B.Fab")
		)
		(pad "1" smd circle
			(at 0.40005 0 90)
			(size 0 0)
			(layers "B.Cu" "B.Mask" "B.Paste")
			(net "FM_BOARD_SKU_ID3")
		)
		(pad "2" smd circle
			(at -0.40005 0 90)
			(size 0 0)
			(layers "B.Cu" "B.Mask" "B.Paste")
			(net "GND")
		)
	)
)
